(kicad_pcb
	(version 20260206)
	(generator "pcbnew")
	(generator_version "10.0")
	(general
		(thickness 1.6)
		(legacy_teardrops no)
	)
	(paper "A4")
	(title_block
		(title "Bryce Canyon_SCC_16316-1_OCP.brd")
		(comment 1 "Bryce Canyon / footprints 414-421 of 1561")
	)
	(layers
		(0 "F.Cu" signal "TOP")
		(4 "In1.Cu" signal "L2GND")
		(6 "In2.Cu" signal "L3")
		(8 "In3.Cu" signal "L4VCC")
		(10 "In4.Cu" signal "L5VCC")
		(12 "In5.Cu" signal "L6")
		(14 "In6.Cu" signal "L7GND")
		(2 "B.Cu" signal "BOTTOM")
		(9 "F.Adhes" user "F.Adhesive")
		(11 "B.Adhes" user "B.Adhesive")
		(13 "F.Paste" user "Package Geometry/Pastemask Top")
		(15 "B.Paste" user "Package Geometry/Pastemask Bottom")
		(5 "F.SilkS" user "Ref Des/Silkscreen Top")
		(7 "B.SilkS" user "Ref Des/Silkscreen Bottom")
		(1 "F.Mask" user "Board Geometry/Soldermask Top")
		(3 "B.Mask" user "Board Geometry/Soldermask Bottom")
		(17 "Dwgs.User" user "User.Drawings")
		(19 "Cmts.User" user "User.Comments")
		(21 "Eco1.User" user "User.Eco1")
		(23 "Eco2.User" user "User.Eco2")
		(25 "Edge.Cuts" user "Board Geometry/Outline")
		(27 "Margin" user)
		(31 "F.CrtYd" user "Package Geometry/Place Bound Top")
		(29 "B.CrtYd" user "Package Geometry/Place Bound Bottom")
		(35 "F.Fab" user "Ref Des/Assembly Top")
		(33 "B.Fab" user "Ref Des/Assembly Bottom")
	)
	(footprint ""
		(layer "F.Cu")
		(at 126.9238 -89.916)
		(property "Reference" "R116"
			(at 0 0 0)
			(layer "F.SilkS")
			(hide yes)
			(effects
				(font
					(size 1.27 1.27)
				)
			)
		)
		(property "Value" "4K75R2F-1-GP"
			(at 0.064008 -3.993896 0)
			(unlocked yes)
			(layer "F.Fab")
			(hide yes)
			(effects
				(font
					(size 1.016 1.016)
					(thickness 0.1524)
				)
			)
		)
		(property "Device Type" "R402H16"
			(at 0.064008 -5.517896 0)
			(unlocked yes)
			(layer "F.Fab")
			(hide yes)
			(effects
				(font
					(size 1.016 1.016)
					(thickness 0.1524)
				)
			)
		)
		(duplicate_pad_numbers_are_jumpers no)
		(fp_line
			(start -0.508 -0.9398)
			(end -0.508 0.9398)
			(stroke
				(width 0.1524)
				(type default)
			)
			(layer "F.SilkS")
		)
		(fp_line
			(start 0.508 -0.9398)
			(end -0.508 -0.9398)
			(stroke
				(width 0.1524)
				(type default)
			)
			(layer "F.SilkS")
		)
		(fp_rect
			(start -0.508 0.9398)
			(end 0.508 -0.9398)
			(stroke
				(width 0)
				(type default)
			)
			(fill no)
			(layer "F.CrtYd")
		)
		(fp_rect
			(start -0.508 0.9398)
			(end 0.508 -0.9398)
			(stroke
				(width 0)
				(type default)
			)
			(fill no)
			(layer "F.Fab")
		)
		(pad "1" smd custom
			(at 0 -0.4445)
			(size 0.1397 0.1397)
			(layers "F.Cu" "F.Mask" "F.Paste")
			(net "P1V8_E")
			(options
				(clearance outline)
				(anchor circle)
			)
			(primitives
				(gr_poly
					(pts
						(arc
							(start -0.1778 -0.2794)
							(mid -0.249642 -0.249642)
							(end -0.2794 -0.1778)
						)
						(arc
							(start -0.2794 0.1778)
							(mid -0.249642 0.249642)
							(end -0.1778 0.2794)
						)
						(arc
							(start 0.1778 0.2794)
							(mid 0.249642 0.249642)
							(end 0.2794 0.1778)
						)
						(arc
							(start 0.2794 -0.1778)
							(mid 0.249642 -0.249642)
							(end 0.1778 -0.2794)
						)
					)
					(width 0)
					(fill yes)
				)
			)
		)
		(pad "2" smd custom
			(at 0 0.4445)
			(size 0.1397 0.1397)
			(layers "F.Cu" "F.Mask" "F.Paste")
			(net "SDB_TX")
			(options
				(clearance outline)
				(anchor circle)
			)
			(primitives
				(gr_poly
					(pts
						(arc
							(start -0.1778 -0.2794)
							(mid -0.249642 -0.249642)
							(end -0.2794 -0.1778)
						)
						(arc
							(start -0.2794 0.1778)
							(mid -0.249642 0.249642)
							(end -0.1778 0.2794)
						)
						(arc
							(start 0.1778 0.2794)
							(mid 0.249642 0.249642)
							(end 0.2794 0.1778)
						)
						(arc
							(start 0.2794 -0.1778)
							(mid 0.249642 -0.249642)
							(end 0.1778 -0.2794)
						)
					)
					(width 0)
					(fill yes)
				)
			)
		)
	)
	(footprint ""
		(layer "F.Cu")
		(at 140.0175 -58.9026)
		(property "Reference" "VIA13"
			(at 0 0 0)
			(layer "F.SilkS")
			(hide yes)
			(effects
				(font
					(size 1.27 1.27)
				)
			)
		)
		(property "Value" "100OHM-8L-1D6MM-L13-GP"
			(at 3.2893 0.0508 0)
			(unlocked yes)
			(layer "F.Fab")
			(hide yes)
			(effects
				(font
					(size 1.016 1.016)
					(thickness 0.1524)
				)
			)
		)
		(property "Device Type" "VIA-PCIE-4P-409091"
			(at 3.2893 -1.4732 0)
			(unlocked yes)
			(layer "F.Fab")
			(hide yes)
			(effects
				(font
					(size 1.016 1.016)
					(thickness 0.1524)
				)
			)
		)
		(duplicate_pad_numbers_are_jumpers no)
		(fp_rect
			(start -2.0447 0.4572)
			(end 2.0447 -0.4572)
			(stroke
				(width 0)
				(type default)
			)
			(fill no)
			(layer "F.CrtYd")
		)
		(fp_rect
			(start -2.0447 0.4572)
			(end 2.0447 -0.4572)
			(stroke
				(width 0)
				(type default)
			)
			(fill no)
			(layer "F.Fab")
		)
		(pad "1" thru_hole circle
			(at -1.5875 0)
			(size 0.508 0.508)
			(drill 0.254)
			(layers "*.Cu" "*.Mask")
			(remove_unused_layers no)
			(net "GND")
			(clearance 0.2032)
			(thermal_gap 0.2032)
		)
		(pad "2" thru_hole circle
			(at -0.5715 0)
			(size 0.508 0.508)
			(drill 0.254)
			(layers "*.Cu" "*.Mask")
			(remove_unused_layers no)
			(net "PHY_IOC_TO_SCC_C_44_DP")
			(clearance 0.2032)
			(thermal_gap 0.2032)
		)
		(pad "3" thru_hole circle
			(at 0.5715 0)
			(size 0.508 0.508)
			(drill 0.254)
			(layers "*.Cu" "*.Mask")
			(remove_unused_layers no)
			(net "PHY_IOC_TO_SCC_C_44_DN")
			(clearance 0.2032)
			(thermal_gap 0.2032)
		)
		(pad "4" thru_hole circle
			(at 1.5875 0)
			(size 0.508 0.508)
			(drill 0.254)
			(layers "*.Cu" "*.Mask")
			(remove_unused_layers no)
			(net "GND")
			(clearance 0.2032)
			(thermal_gap 0.2032)
		)
	)
	(footprint ""
		(layer "F.Cu")
		(at 10.9728 -66.5226 90)
		(property "Reference" "R608"
			(at 0 0 90)
			(layer "F.SilkS")
			(hide yes)
			(effects
				(font
					(size 1.27 1.27)
				)
			)
		)
		(property "Value" "10KR2F-2-GP"
			(at 0.064008 -3.993896 90)
			(unlocked yes)
			(layer "F.Fab")
			(hide yes)
			(effects
				(font
					(size 1.016 1.016)
					(thickness 0.1524)
				)
			)
		)
		(property "Device Type" "R402H16"
			(at 0.064008 -5.517896 90)
			(unlocked yes)
			(layer "F.Fab")
			(hide yes)
			(effects
				(font
					(size 1.016 1.016)
					(thickness 0.1524)
				)
			)
		)
		(duplicate_pad_numbers_are_jumpers no)
		(fp_line
			(start 0.508 -0.9398)
			(end -0.508 -0.9398)
			(stroke
				(width 0.1524)
				(type default)
			)
			(layer "F.SilkS")
		)
		(fp_line
			(start -0.508 -0.9398)
			(end -0.508 0.9398)
			(stroke
				(width 0.1524)
				(type default)
			)
			(layer "F.SilkS")
		)
		(fp_rect
			(start -0.508 0.9398)
			(end 0.508 -0.9398)
			(stroke
				(width 0)
				(type default)
			)
			(fill no)
			(layer "F.CrtYd")
		)
		(fp_rect
			(start -0.508 0.9398)
			(end 0.508 -0.9398)
			(stroke
				(width 0)
				(type default)
			)
			(fill no)
			(layer "F.Fab")
		)
		(pad "1" smd custom
			(at 0 -0.4445 90)
			(size 0.1397 0.1397)
			(layers "F.Cu" "F.Mask" "F.Paste")
			(net "SCC_HSC_N")
			(options
				(clearance outline)
				(anchor circle)
			)
			(primitives
				(gr_poly
					(pts
						(arc
							(start -0.1778 -0.2794)
							(mid -0.249642 -0.249642)
							(end -0.2794 -0.1778)
						)
						(arc
							(start -0.2794 0.1778)
							(mid -0.249642 0.249642)
							(end -0.1778 0.2794)
						)
						(arc
							(start 0.1778 0.2794)
							(mid 0.249642 0.249642)
							(end 0.2794 0.1778)
						)
						(arc
							(start 0.2794 -0.1778)
							(mid 0.249642 -0.249642)
							(end 0.1778 -0.2794)
						)
					)
					(width 0)
					(fill yes)
				)
			)
		)
		(pad "2" smd custom
			(at 0 0.4445 90)
			(size 0.1397 0.1397)
			(layers "F.Cu" "F.Mask" "F.Paste")
			(net "P12V_MAIN")
			(options
				(clearance outline)
				(anchor circle)
			)
			(primitives
				(gr_poly
					(pts
						(arc
							(start -0.1778 -0.2794)
							(mid -0.249642 -0.249642)
							(end -0.2794 -0.1778)
						)
						(arc
							(start -0.2794 0.1778)
							(mid -0.249642 0.249642)
							(end -0.1778 0.2794)
						)
						(arc
							(start 0.1778 0.2794)
							(mid 0.249642 0.249642)
							(end 0.2794 0.1778)
						)
						(arc
							(start 0.2794 -0.1778)
							(mid 0.249642 -0.249642)
							(end 0.1778 -0.2794)
						)
					)
					(width 0)
					(fill yes)
				)
			)
		)
	)
	(footprint ""
		(layer "F.Cu")
		(at 13.9192 -93.5736)
		(property "Reference" "R432"
			(at 0 0 0)
			(layer "F.SilkS")
			(hide yes)
			(effects
				(font
					(size 1.27 1.27)
				)
			)
		)
		(property "Value" "1KR2F-3-GP"
			(at 0.064008 -3.993896 0)
			(unlocked yes)
			(layer "F.Fab")
			(hide yes)
			(effects
				(font
					(size 1.016 1.016)
					(thickness 0.1524)
				)
			)
		)
		(property "Device Type" "R402H16"
			(at 0.064008 -5.517896 0)
			(unlocked yes)
			(layer "F.Fab")
			(hide yes)
			(effects
				(font
					(size 1.016 1.016)
					(thickness 0.1524)
				)
			)
		)
		(duplicate_pad_numbers_are_jumpers no)
		(fp_line
			(start -0.508 -0.9398)
			(end -0.508 0.9398)
			(stroke
				(width 0.1524)
				(type default)
			)
			(layer "F.SilkS")
		)
		(fp_line
			(start 0.508 -0.9398)
			(end -0.508 -0.9398)
			(stroke
				(width 0.1524)
				(type default)
			)
			(layer "F.SilkS")
		)
		(fp_rect
			(start -0.508 0.9398)
			(end 0.508 -0.9398)
			(stroke
				(width 0)
				(type default)
			)
			(fill no)
			(layer "F.CrtYd")
		)
		(fp_rect
			(start -0.508 0.9398)
			(end 0.508 -0.9398)
			(stroke
				(width 0)
				(type default)
			)
			(fill no)
			(layer "F.Fab")
		)
		(pad "1" smd custom
			(at 0 -0.4445)
			(size 0.1397 0.1397)
			(layers "F.Cu" "F.Mask" "F.Paste")
			(net "P3V3")
			(options
				(clearance outline)
				(anchor circle)
			)
			(primitives
				(gr_poly
					(pts
						(arc
							(start -0.1778 -0.2794)
							(mid -0.249642 -0.249642)
							(end -0.2794 -0.1778)
						)
						(arc
							(start -0.2794 0.1778)
							(mid -0.249642 0.249642)
							(end -0.1778 0.2794)
						)
						(arc
							(start 0.1778 0.2794)
							(mid 0.249642 0.249642)
							(end 0.2794 0.1778)
						)
						(arc
							(start 0.2794 -0.1778)
							(mid 0.249642 -0.249642)
							(end 0.1778 -0.2794)
						)
					)
					(width 0)
					(fill yes)
				)
			)
		)
		(pad "2" smd custom
			(at 0 0.4445)
			(size 0.1397 0.1397)
			(layers "F.Cu" "F.Mask" "F.Paste")
			(net "I2C_DPB_SCL3")
			(options
				(clearance outline)
				(anchor circle)
			)
			(primitives
				(gr_poly
					(pts
						(arc
							(start -0.1778 -0.2794)
							(mid -0.249642 -0.249642)
							(end -0.2794 -0.1778)
						)
						(arc
							(start -0.2794 0.1778)
							(mid -0.249642 0.249642)
							(end -0.1778 0.2794)
						)
						(arc
							(start 0.1778 0.2794)
							(mid 0.249642 0.249642)
							(end 0.2794 0.1778)
						)
						(arc
							(start 0.2794 -0.1778)
							(mid 0.249642 -0.249642)
							(end 0.1778 -0.2794)
						)
					)
					(width 0)
					(fill yes)
				)
			)
		)
	)
	(footprint ""
		(layer "F.Cu")
		(at 190.759842 -23.32101 180)
		(property "Reference" "R249"
			(at 0 0 180)
			(layer "F.SilkS")
			(hide yes)
			(effects
				(font
					(size 1.27 1.27)
				)
			)
		)
		(property "Value" "10KR2F-2-GP"
			(at 0.064008 -3.993896 180)
			(unlocked yes)
			(layer "F.Fab")
			(hide yes)
			(effects
				(font
					(size 1.016 1.016)
					(thickness 0.1524)
				)
			)
		)
		(property "Device Type" "R402H16"
			(at 0.064008 -5.517896 180)
			(unlocked yes)
			(layer "F.Fab")
			(hide yes)
			(effects
				(font
					(size 1.016 1.016)
					(thickness 0.1524)
				)
			)
		)
		(duplicate_pad_numbers_are_jumpers no)
		(fp_line
			(start 0.508 -0.9398)
			(end -0.508 -0.9398)
			(stroke
				(width 0.1524)
				(type default)
			)
			(layer "F.SilkS")
		)
		(fp_line
			(start -0.508 -0.9398)
			(end -0.508 0.9398)
			(stroke
				(width 0.1524)
				(type default)
			)
			(layer "F.SilkS")
		)
		(fp_rect
			(start -0.508 0.9398)
			(end 0.508 -0.9398)
			(stroke
				(width 0)
				(type default)
			)
			(fill no)
			(layer "F.CrtYd")
		)
		(fp_rect
			(start -0.508 0.9398)
			(end 0.508 -0.9398)
			(stroke
				(width 0)
				(type default)
			)
			(fill no)
			(layer "F.Fab")
		)
		(pad "1" smd custom
			(at 0 -0.4445 180)
			(size 0.1397 0.1397)
			(layers "F.Cu" "F.Mask" "F.Paste")
			(net "P1V8_C")
			(options
				(clearance outline)
				(anchor circle)
			)
			(primitives
				(gr_poly
					(pts
						(arc
							(start -0.1778 -0.2794)
							(mid -0.249642 -0.249642)
							(end -0.2794 -0.1778)
						)
						(arc
							(start -0.2794 0.1778)
							(mid -0.249642 0.249642)
							(end -0.1778 0.2794)
						)
						(arc
							(start 0.1778 0.2794)
							(mid 0.249642 0.249642)
							(end 0.2794 0.1778)
						)
						(arc
							(start 0.2794 -0.1778)
							(mid 0.249642 -0.249642)
							(end 0.1778 -0.2794)
						)
					)
					(width 0)
					(fill yes)
				)
			)
		)
		(pad "2" smd custom
			(at 0 0.4445 180)
			(size 0.1397 0.1397)
			(layers "F.Cu" "F.Mask" "F.Paste")
			(net "SYS_DBMODE2")
			(options
				(clearance outline)
				(anchor circle)
			)
			(primitives
				(gr_poly
					(pts
						(arc
							(start -0.1778 -0.2794)
							(mid -0.249642 -0.249642)
							(end -0.2794 -0.1778)
						)
						(arc
							(start -0.2794 0.1778)
							(mid -0.249642 0.249642)
							(end -0.1778 0.2794)
						)
						(arc
							(start 0.1778 0.2794)
							(mid 0.249642 0.249642)
							(end 0.2794 0.1778)
						)
						(arc
							(start 0.2794 -0.1778)
							(mid 0.249642 -0.249642)
							(end 0.1778 -0.2794)
						)
					)
					(width 0)
					(fill yes)
				)
			)
		)
	)
	(footprint ""
		(layer "F.Cu")
		(at 66.04 -72.6948 180)
		(property "Reference" "R428"
			(at 0 0 180)
			(layer "F.SilkS")
			(hide yes)
			(effects
				(font
					(size 1.27 1.27)
				)
			)
		)
		(property "Value" "1KR2F-3-GP"
			(at 0.064008 -3.993896 180)
			(unlocked yes)
			(layer "F.Fab")
			(hide yes)
			(effects
				(font
					(size 1.016 1.016)
					(thickness 0.1524)
				)
			)
		)
		(property "Device Type" "R402H16"
			(at 0.064008 -5.517896 180)
			(unlocked yes)
			(layer "F.Fab")
			(hide yes)
			(effects
				(font
					(size 1.016 1.016)
					(thickness 0.1524)
				)
			)
		)
		(duplicate_pad_numbers_are_jumpers no)
		(fp_line
			(start 0.508 -0.9398)
			(end -0.508 -0.9398)
			(stroke
				(width 0.1524)
				(type default)
			)
			(layer "F.SilkS")
		)
		(fp_line
			(start -0.508 -0.9398)
			(end -0.508 0.9398)
			(stroke
				(width 0.1524)
				(type default)
			)
			(layer "F.SilkS")
		)
		(fp_rect
			(start -0.508 0.9398)
			(end 0.508 -0.9398)
			(stroke
				(width 0)
				(type default)
			)
			(fill no)
			(layer "F.CrtYd")
		)
		(fp_rect
			(start -0.508 0.9398)
			(end 0.508 -0.9398)
			(stroke
				(width 0)
				(type default)
			)
			(fill no)
			(layer "F.Fab")
		)
		(pad "1" smd custom
			(at 0 -0.4445 180)
			(size 0.1397 0.1397)
			(layers "F.Cu" "F.Mask" "F.Paste")
			(net "P3V3")
			(options
				(clearance outline)
				(anchor circle)
			)
			(primitives
				(gr_poly
					(pts
						(arc
							(start -0.1778 -0.2794)
							(mid -0.249642 -0.249642)
							(end -0.2794 -0.1778)
						)
						(arc
							(start -0.2794 0.1778)
							(mid -0.249642 0.249642)
							(end -0.1778 0.2794)
						)
						(arc
							(start 0.1778 0.2794)
							(mid 0.249642 0.249642)
							(end 0.2794 0.1778)
						)
						(arc
							(start 0.2794 -0.1778)
							(mid 0.249642 -0.249642)
							(end 0.1778 -0.2794)
						)
					)
					(width 0)
					(fill yes)
				)
			)
		)
		(pad "2" smd custom
			(at 0 0.4445 180)
			(size 0.1397 0.1397)
			(layers "F.Cu" "F.Mask" "F.Paste")
			(net "I2C_DRIVE_FLT_LED_SDA6")
			(options
				(clearance outline)
				(anchor circle)
			)
			(primitives
				(gr_poly
					(pts
						(arc
							(start -0.1778 -0.2794)
							(mid -0.249642 -0.249642)
							(end -0.2794 -0.1778)
						)
						(arc
							(start -0.2794 0.1778)
							(mid -0.249642 0.249642)
							(end -0.1778 0.2794)
						)
						(arc
							(start 0.1778 0.2794)
							(mid 0.249642 0.249642)
							(end 0.2794 0.1778)
						)
						(arc
							(start 0.2794 -0.1778)
							(mid 0.249642 -0.249642)
							(end 0.1778 -0.2794)
						)
					)
					(width 0)
					(fill yes)
				)
			)
		)
	)
	(footprint ""
		(layer "F.Cu")
		(at 94.661228 -83.439762 -90)
		(property "Reference" "R309"
			(at 0 0 270)
			(layer "F.SilkS")
			(hide yes)
			(effects
				(font
					(size 1.27 1.27)
				)
			)
		)
		(property "Value" "10KR2F-2-GP"
			(at 0.064008 -3.993896 270)
			(unlocked yes)
			(layer "F.Fab")
			(hide yes)
			(effects
				(font
					(size 1.016 1.016)
					(thickness 0.1524)
				)
			)
		)
		(property "Device Type" "R402H16"
			(at 0.064008 -5.517896 270)
			(unlocked yes)
			(layer "F.Fab")
			(hide yes)
			(effects
				(font
					(size 1.016 1.016)
					(thickness 0.1524)
				)
			)
		)
		(duplicate_pad_numbers_are_jumpers no)
		(fp_line
			(start -0.508 -0.9398)
			(end -0.508 0.9398)
			(stroke
				(width 0.1524)
				(type default)
			)
			(layer "F.SilkS")
		)
		(fp_line
			(start 0.508 -0.9398)
			(end -0.508 -0.9398)
			(stroke
				(width 0.1524)
				(type default)
			)
			(layer "F.SilkS")
		)
		(fp_rect
			(start -0.508 0.9398)
			(end 0.508 -0.9398)
			(stroke
				(width 0)
				(type default)
			)
			(fill no)
			(layer "F.CrtYd")
		)
		(fp_rect
			(start -0.508 0.9398)
			(end 0.508 -0.9398)
			(stroke
				(width 0)
				(type default)
			)
			(fill no)
			(layer "F.Fab")
		)
		(pad "1" smd custom
			(at 0 -0.4445 270)
			(size 0.1397 0.1397)
			(layers "F.Cu" "F.Mask" "F.Paste")
			(net "P1V8_E")
			(options
				(clearance outline)
				(anchor circle)
			)
			(primitives
				(gr_poly
					(pts
						(arc
							(start -0.1778 -0.2794)
							(mid -0.249642 -0.249642)
							(end -0.2794 -0.1778)
						)
						(arc
							(start -0.2794 0.1778)
							(mid -0.249642 0.249642)
							(end -0.1778 0.2794)
						)
						(arc
							(start 0.1778 0.2794)
							(mid 0.249642 0.249642)
							(end 0.2794 0.1778)
						)
						(arc
							(start 0.2794 -0.1778)
							(mid 0.249642 -0.249642)
							(end 0.1778 -0.2794)
						)
					)
					(width 0)
					(fill yes)
				)
			)
		)
		(pad "2" smd custom
			(at 0 0.4445 270)
			(size 0.1397 0.1397)
			(layers "F.Cu" "F.Mask" "F.Paste")
			(net "SCC_RESET_LS_N")
			(options
				(clearance outline)
				(anchor circle)
			)
			(primitives
				(gr_poly
					(pts
						(arc
							(start -0.1778 -0.2794)
							(mid -0.249642 -0.249642)
							(end -0.2794 -0.1778)
						)
						(arc
							(start -0.2794 0.1778)
							(mid -0.249642 0.249642)
							(end -0.1778 0.2794)
						)
						(arc
							(start 0.1778 0.2794)
							(mid 0.249642 0.249642)
							(end 0.2794 0.1778)
						)
						(arc
							(start 0.2794 -0.1778)
							(mid 0.249642 -0.249642)
							(end 0.1778 -0.2794)
						)
					)
					(width 0)
					(fill yes)
				)
			)
		)
	)
	(footprint ""
		(layer "F.Cu")
		(at 190.155576 -48.526954 90)
		(property "Reference" "TP103"
			(at 0 0 90)
			(layer "F.SilkS")
			(hide yes)
			(effects
				(font
					(size 1.27 1.27)
				)
			)
		)
		(property "Value" "TPAD28-2-GP"
			(at -0.0127 -1.6637 90)
			(unlocked yes)
			(layer "F.Fab")
			(hide yes)
			(effects
				(font
					(size 1.016 1.016)
					(thickness 0.1524)
				)
			)
		)
		(property "Device Type" "TPAD28"
			(at -0.0127 -3.1877 90)
			(unlocked yes)
			(layer "F.Fab")
			(hide yes)
			(effects
				(font
					(size 1.016 1.016)
					(thickness 0.1524)
				)
			)
		)
		(duplicate_pad_numbers_are_jumpers no)
		(fp_poly
			(pts
				(arc
					(start 0 0.3556)
					(mid 0 -0.3556)
					(end 0 0.3556)
				)
			)
			(stroke
				(width 0)
				(type default)
			)
			(fill no)
			(layer "F.CrtYd")
		)
		(fp_poly
			(pts
				(arc
					(start 0 0.6096)
					(mid 0 -0.6096)
					(end 0 0.6096)
				)
			)
			(stroke
				(width 0)
				(type default)
			)
			(fill no)
			(layer "F.Fab")
		)
		(pad "1" smd circle
			(at 0 0 90)
			(size 0.7112 0.7112)
			(layers "F.Cu" "F.Mask" "F.Paste")
			(net "XM_ADDR_16")
		)
	)
)
